(kicad_pcb
	(version 20260206)
	(generator "pcbnew")
	(generator_version "10.0")
	(general
		(thickness 1.6)
		(legacy_teardrops no)
	)
	(paper "A4")
	(title_block
		(title "04192023_DAF0TMB3IC0_F0TG_MB_C_brd_V02_OCP.brd")
		(comment 1 "Grand Teton / footprints 2320-2326 of 8354")
	)
	(layers
		(0 "F.Cu" signal "TOP")
		(4 "In1.Cu" signal "GND")
		(6 "In2.Cu" signal "IN1")
		(8 "In3.Cu" signal "GND1")
		(10 "In4.Cu" signal "IN2")
		(12 "In5.Cu" signal "GND2")
		(14 "In6.Cu" signal "IN3")
		(16 "In7.Cu" signal "GND3")
		(18 "In8.Cu" signal "VCC")
		(20 "In9.Cu" signal "VCC1")
		(22 "In10.Cu" signal "GND4")
		(24 "In11.Cu" signal "IN4")
		(26 "In12.Cu" signal "GND5")
		(28 "In13.Cu" signal "IN5")
		(30 "In14.Cu" signal "GND6")
		(32 "In15.Cu" signal "IN6")
		(34 "In16.Cu" signal "GND7")
		(2 "B.Cu" signal "BOTTOM")
		(9 "F.Adhes" user "F.Adhesive")
		(11 "B.Adhes" user "B.Adhesive")
		(13 "F.Paste" user "Package Geometry/Pastemask Top")
		(15 "B.Paste" user "Package Geometry/Pastemask Bottom")
		(5 "F.SilkS" user "Ref Des/Silkscreen Top")
		(7 "B.SilkS" user "Ref Des/Silkscreen Bottom")
		(1 "F.Mask" user "Board Geometry/Soldermask Top")
		(3 "B.Mask" user "Board Geometry/Soldermask Bottom")
		(17 "Dwgs.User" user "User.Drawings")
		(19 "Cmts.User" user "User.Comments")
		(21 "Eco1.User" user "User.Eco1")
		(23 "Eco2.User" user "User.Eco2")
		(25 "Edge.Cuts" user "Board Geometry/Outline")
		(27 "Margin" user)
		(31 "F.CrtYd" user "Package Geometry/Place Bound Top")
		(29 "B.CrtYd" user "Package Geometry/Place Bound Bottom")
		(35 "F.Fab" user "Ref Des/Assembly Top")
		(33 "B.Fab" user "Ref Des/Assembly Bottom")
	)
	(footprint ""
		(layer "F.Cu")
		(at 296.52595 -150.538942 180)
		(property "Reference" "R1298"
			(at 0 0 180)
			(layer "F.SilkS")
			(hide yes)
			(effects
				(font
					(size 1.27 1.27)
				)
			)
		)
		(property "Value" ""
			(at 0 0 180)
			(layer "F.Fab")
			(effects
				(font
					(size 1.27 1.27)
				)
			)
		)
		(duplicate_pad_numbers_are_jumpers no)
		(fp_line
			(start 0.7874 0.4064)
			(end -0.7874 0.4064)
			(stroke
				(width 0.1524)
				(type default)
			)
			(layer "F.SilkS")
		)
		(fp_line
			(start 0.7874 -0.4064)
			(end 0.7874 0.4064)
			(stroke
				(width 0.1524)
				(type default)
			)
			(layer "F.SilkS")
		)
		(fp_line
			(start -0.7874 0.4064)
			(end -0.7874 -0.4064)
			(stroke
				(width 0.1524)
				(type default)
			)
			(layer "F.SilkS")
		)
		(fp_line
			(start -0.7874 -0.4064)
			(end 0.7874 -0.4064)
			(stroke
				(width 0.1524)
				(type default)
			)
			(layer "F.SilkS")
		)
		(fp_line
			(start 0.67945 0.3048)
			(end 0.120396 0.3048)
			(stroke
				(width 0.1)
				(type default)
			)
			(layer "F.Fab")
		)
		(fp_line
			(start 0.67945 -0.3048)
			(end 0.67945 0.3048)
			(stroke
				(width 0.1)
				(type default)
			)
			(layer "F.Fab")
		)
		(fp_line
			(start 0.12065 -0.2794)
			(end 0.12065 -0.3048)
			(stroke
				(width 0.1)
				(type default)
			)
			(layer "F.Fab")
		)
		(fp_line
			(start 0.12065 -0.3048)
			(end 0.67945 -0.3048)
			(stroke
				(width 0.1)
				(type default)
			)
			(layer "F.Fab")
		)
		(fp_line
			(start 0.120396 0.3048)
			(end 0.120396 0.2794)
			(stroke
				(width 0.1)
				(type default)
			)
			(layer "F.Fab")
		)
		(fp_line
			(start 0.120396 0.2794)
			(end -0.12065 0.2794)
			(stroke
				(width 0.1)
				(type default)
			)
			(layer "F.Fab")
		)
		(fp_line
			(start -0.12065 0.3048)
			(end -0.67945 0.3048)
			(stroke
				(width 0.1)
				(type default)
			)
			(layer "F.Fab")
		)
		(fp_line
			(start -0.12065 0.2794)
			(end -0.12065 0.3048)
			(stroke
				(width 0.1)
				(type default)
			)
			(layer "F.Fab")
		)
		(fp_line
			(start -0.12065 -0.2794)
			(end 0.12065 -0.2794)
			(stroke
				(width 0.1)
				(type default)
			)
			(layer "F.Fab")
		)
		(fp_line
			(start -0.12065 -0.305054)
			(end -0.12065 -0.2794)
			(stroke
				(width 0.1)
				(type default)
			)
			(layer "F.Fab")
		)
		(fp_line
			(start -0.67945 0.3048)
			(end -0.67945 -0.305054)
			(stroke
				(width 0.1)
				(type default)
			)
			(layer "F.Fab")
		)
		(fp_line
			(start -0.67945 -0.305054)
			(end -0.12065 -0.305054)
			(stroke
				(width 0.1)
				(type default)
			)
			(layer "F.Fab")
		)
		(pad "1" smd rect
			(at -0.40005 0)
			(size 0.4572 0.508)
			(layers "F.Cu" "F.Mask" "F.Paste")
			(net "I3C_SPD_DDRAF_CPU0_SDA")
		)
		(pad "2" smd rect
			(at 0.40005 0)
			(size 0.4572 0.508)
			(layers "F.Cu" "F.Mask" "F.Paste")
			(net "I3C_SPD_DDRAF_CPU0_LVC1_SDA")
		)
	)
	(footprint ""
		(layer "F.Cu")
		(at 392.962384 -393.47648 180)
		(property "Reference" "R1087"
			(at 0 0 180)
			(layer "F.SilkS")
			(hide yes)
			(effects
				(font
					(size 1.27 1.27)
				)
			)
		)
		(property "Value" ""
			(at 0 0 180)
			(layer "F.Fab")
			(effects
				(font
					(size 1.27 1.27)
				)
			)
		)
		(duplicate_pad_numbers_are_jumpers no)
		(fp_line
			(start 0.7874 0.4064)
			(end -0.7874 0.4064)
			(stroke
				(width 0.1524)
				(type default)
			)
			(layer "F.SilkS")
		)
		(fp_line
			(start 0.7874 -0.4064)
			(end 0.7874 0.4064)
			(stroke
				(width 0.1524)
				(type default)
			)
			(layer "F.SilkS")
		)
		(fp_line
			(start -0.7874 0.4064)
			(end -0.7874 -0.4064)
			(stroke
				(width 0.1524)
				(type default)
			)
			(layer "F.SilkS")
		)
		(fp_line
			(start -0.7874 -0.4064)
			(end 0.7874 -0.4064)
			(stroke
				(width 0.1524)
				(type default)
			)
			(layer "F.SilkS")
		)
		(fp_line
			(start 0.67945 0.3048)
			(end 0.120396 0.3048)
			(stroke
				(width 0.1)
				(type default)
			)
			(layer "F.Fab")
		)
		(fp_line
			(start 0.67945 -0.3048)
			(end 0.67945 0.3048)
			(stroke
				(width 0.1)
				(type default)
			)
			(layer "F.Fab")
		)
		(fp_line
			(start 0.12065 -0.2794)
			(end 0.12065 -0.3048)
			(stroke
				(width 0.1)
				(type default)
			)
			(layer "F.Fab")
		)
		(fp_line
			(start 0.12065 -0.3048)
			(end 0.67945 -0.3048)
			(stroke
				(width 0.1)
				(type default)
			)
			(layer "F.Fab")
		)
		(fp_line
			(start 0.120396 0.3048)
			(end 0.120396 0.2794)
			(stroke
				(width 0.1)
				(type default)
			)
			(layer "F.Fab")
		)
		(fp_line
			(start 0.120396 0.2794)
			(end -0.12065 0.2794)
			(stroke
				(width 0.1)
				(type default)
			)
			(layer "F.Fab")
		)
		(fp_line
			(start -0.12065 0.3048)
			(end -0.67945 0.3048)
			(stroke
				(width 0.1)
				(type default)
			)
			(layer "F.Fab")
		)
		(fp_line
			(start -0.12065 0.2794)
			(end -0.12065 0.3048)
			(stroke
				(width 0.1)
				(type default)
			)
			(layer "F.Fab")
		)
		(fp_line
			(start -0.12065 -0.2794)
			(end 0.12065 -0.2794)
			(stroke
				(width 0.1)
				(type default)
			)
			(layer "F.Fab")
		)
		(fp_line
			(start -0.12065 -0.305054)
			(end -0.12065 -0.2794)
			(stroke
				(width 0.1)
				(type default)
			)
			(layer "F.Fab")
		)
		(fp_line
			(start -0.67945 0.3048)
			(end -0.67945 -0.305054)
			(stroke
				(width 0.1)
				(type default)
			)
			(layer "F.Fab")
		)
		(fp_line
			(start -0.67945 -0.305054)
			(end -0.12065 -0.305054)
			(stroke
				(width 0.1)
				(type default)
			)
			(layer "F.Fab")
		)
		(pad "1" smd rect
			(at -0.40005 0)
			(size 0.4572 0.508)
			(layers "F.Cu" "F.Mask" "F.Paste")
			(net "P1V8_CPU0_RT3_1A_1D")
		)
		(pad "2" smd rect
			(at 0.40005 0)
			(size 0.4572 0.508)
			(layers "F.Cu" "F.Mask" "F.Paste")
			(net "P1V8_CPU0_RT3_1A")
		)
	)
	(footprint ""
		(layer "F.Cu")
		(at 415.628582 -333.215996 180)
		(property "Reference" "PR114"
			(at 0 0 180)
			(layer "F.SilkS")
			(hide yes)
			(effects
				(font
					(size 1.27 1.27)
				)
			)
		)
		(property "Value" ""
			(at 0 0 180)
			(layer "F.Fab")
			(effects
				(font
					(size 1.27 1.27)
				)
			)
		)
		(duplicate_pad_numbers_are_jumpers no)
		(fp_line
			(start 0.7874 0.4064)
			(end -0.7874 0.4064)
			(stroke
				(width 0.1524)
				(type default)
			)
			(layer "F.SilkS")
		)
		(fp_line
			(start 0.7874 -0.4064)
			(end 0.7874 0.4064)
			(stroke
				(width 0.1524)
				(type default)
			)
			(layer "F.SilkS")
		)
		(fp_line
			(start -0.7874 0.4064)
			(end -0.7874 -0.4064)
			(stroke
				(width 0.1524)
				(type default)
			)
			(layer "F.SilkS")
		)
		(fp_line
			(start -0.7874 -0.4064)
			(end 0.7874 -0.4064)
			(stroke
				(width 0.1524)
				(type default)
			)
			(layer "F.SilkS")
		)
		(fp_line
			(start 0.67945 0.3048)
			(end 0.120396 0.3048)
			(stroke
				(width 0.1)
				(type default)
			)
			(layer "F.Fab")
		)
		(fp_line
			(start 0.67945 -0.3048)
			(end 0.67945 0.3048)
			(stroke
				(width 0.1)
				(type default)
			)
			(layer "F.Fab")
		)
		(fp_line
			(start 0.12065 -0.2794)
			(end 0.12065 -0.3048)
			(stroke
				(width 0.1)
				(type default)
			)
			(layer "F.Fab")
		)
		(fp_line
			(start 0.12065 -0.3048)
			(end 0.67945 -0.3048)
			(stroke
				(width 0.1)
				(type default)
			)
			(layer "F.Fab")
		)
		(fp_line
			(start 0.120396 0.3048)
			(end 0.120396 0.2794)
			(stroke
				(width 0.1)
				(type default)
			)
			(layer "F.Fab")
		)
		(fp_line
			(start 0.120396 0.2794)
			(end -0.12065 0.2794)
			(stroke
				(width 0.1)
				(type default)
			)
			(layer "F.Fab")
		)
		(fp_line
			(start -0.12065 0.3048)
			(end -0.67945 0.3048)
			(stroke
				(width 0.1)
				(type default)
			)
			(layer "F.Fab")
		)
		(fp_line
			(start -0.12065 0.2794)
			(end -0.12065 0.3048)
			(stroke
				(width 0.1)
				(type default)
			)
			(layer "F.Fab")
		)
		(fp_line
			(start -0.12065 -0.2794)
			(end 0.12065 -0.2794)
			(stroke
				(width 0.1)
				(type default)
			)
			(layer "F.Fab")
		)
		(fp_line
			(start -0.12065 -0.305054)
			(end -0.12065 -0.2794)
			(stroke
				(width 0.1)
				(type default)
			)
			(layer "F.Fab")
		)
		(fp_line
			(start -0.67945 0.3048)
			(end -0.67945 -0.305054)
			(stroke
				(width 0.1)
				(type default)
			)
			(layer "F.Fab")
		)
		(fp_line
			(start -0.67945 -0.305054)
			(end -0.12065 -0.305054)
			(stroke
				(width 0.1)
				(type default)
			)
			(layer "F.Fab")
		)
		(pad "1" smd circle
			(at -0.40005 0 180)
			(size 0 0)
			(layers "F.Cu" "F.Mask" "F.Paste")
			(net "PVDD11_S3_P0")
		)
		(pad "2" smd circle
			(at 0.40005 0 180)
			(size 0 0)
			(layers "F.Cu" "F.Mask" "F.Paste")
			(net "VSENSE_PVDD11_S3_P0_DP")
		)
	)
	(footprint ""
		(layer "F.Cu")
		(at 415.834322 -158.556198)
		(property "Reference" "PR365"
			(at 0 0 0)
			(layer "F.SilkS")
			(hide yes)
			(effects
				(font
					(size 1.27 1.27)
				)
			)
		)
		(property "Value" ""
			(at 0 0 0)
			(layer "F.Fab")
			(effects
				(font
					(size 1.27 1.27)
				)
			)
		)
		(duplicate_pad_numbers_are_jumpers no)
		(fp_line
			(start -0.7874 -0.4064)
			(end 0.7874 -0.4064)
			(stroke
				(width 0.1524)
				(type default)
			)
			(layer "F.SilkS")
		)
		(fp_line
			(start -0.7874 0.4064)
			(end -0.7874 -0.4064)
			(stroke
				(width 0.1524)
				(type default)
			)
			(layer "F.SilkS")
		)
		(fp_line
			(start 0.7874 -0.4064)
			(end 0.7874 0.4064)
			(stroke
				(width 0.1524)
				(type default)
			)
			(layer "F.SilkS")
		)
		(fp_line
			(start 0.7874 0.4064)
			(end -0.7874 0.4064)
			(stroke
				(width 0.1524)
				(type default)
			)
			(layer "F.SilkS")
		)
		(fp_line
			(start -0.67945 -0.305054)
			(end -0.12065 -0.305054)
			(stroke
				(width 0.1)
				(type default)
			)
			(layer "F.Fab")
		)
		(fp_line
			(start -0.67945 0.3048)
			(end -0.67945 -0.305054)
			(stroke
				(width 0.1)
				(type default)
			)
			(layer "F.Fab")
		)
		(fp_line
			(start -0.12065 -0.305054)
			(end -0.12065 -0.2794)
			(stroke
				(width 0.1)
				(type default)
			)
			(layer "F.Fab")
		)
		(fp_line
			(start -0.12065 -0.2794)
			(end 0.12065 -0.2794)
			(stroke
				(width 0.1)
				(type default)
			)
			(layer "F.Fab")
		)
		(fp_line
			(start -0.12065 0.2794)
			(end -0.12065 0.3048)
			(stroke
				(width 0.1)
				(type default)
			)
			(layer "F.Fab")
		)
		(fp_line
			(start -0.12065 0.3048)
			(end -0.67945 0.3048)
			(stroke
				(width 0.1)
				(type default)
			)
			(layer "F.Fab")
		)
		(fp_line
			(start 0.120396 0.2794)
			(end -0.12065 0.2794)
			(stroke
				(width 0.1)
				(type default)
			)
			(layer "F.Fab")
		)
		(fp_line
			(start 0.120396 0.3048)
			(end 0.120396 0.2794)
			(stroke
				(width 0.1)
				(type default)
			)
			(layer "F.Fab")
		)
		(fp_line
			(start 0.12065 -0.3048)
			(end 0.67945 -0.3048)
			(stroke
				(width 0.1)
				(type default)
			)
			(layer "F.Fab")
		)
		(fp_line
			(start 0.12065 -0.2794)
			(end 0.12065 -0.3048)
			(stroke
				(width 0.1)
				(type default)
			)
			(layer "F.Fab")
		)
		(fp_line
			(start 0.67945 -0.3048)
			(end 0.67945 0.3048)
			(stroke
				(width 0.1)
				(type default)
			)
			(layer "F.Fab")
		)
		(fp_line
			(start 0.67945 0.3048)
			(end 0.120396 0.3048)
			(stroke
				(width 0.1)
				(type default)
			)
			(layer "F.Fab")
		)
		(pad "1" smd circle
			(at -0.40005 0)
			(size 0 0)
			(layers "F.Cu" "F.Mask" "F.Paste")
			(net "GND")
		)
		(pad "2" smd circle
			(at 0.40005 0)
			(size 0 0)
			(layers "F.Cu" "F.Mask" "F.Paste")
			(net "PVDDCR_SOC_P0_LSET3")
		)
	)
	(footprint ""
		(layer "F.Cu")
		(at 87.04834 -182.578248 90)
		(property "Reference" "PC263_2"
			(at 0 0 90)
			(layer "F.SilkS")
			(hide yes)
			(effects
				(font
					(size 1.27 1.27)
				)
			)
		)
		(property "Value" ""
			(at 0 0 90)
			(layer "F.Fab")
			(effects
				(font
					(size 1.27 1.27)
				)
			)
		)
		(duplicate_pad_numbers_are_jumpers no)
		(fp_line
			(start 0.7874 -0.4064)
			(end 0.7874 0.4064)
			(stroke
				(width 0.1524)
				(type default)
			)
			(layer "F.SilkS")
		)
		(fp_line
			(start -0.7874 -0.4064)
			(end 0.7874 -0.4064)
			(stroke
				(width 0.1524)
				(type default)
			)
			(layer "F.SilkS")
		)
		(fp_line
			(start 0.7874 0.4064)
			(end -0.7874 0.4064)
			(stroke
				(width 0.1524)
				(type default)
			)
			(layer "F.SilkS")
		)
		(fp_line
			(start -0.7874 0.4064)
			(end -0.7874 -0.4064)
			(stroke
				(width 0.1524)
				(type default)
			)
			(layer "F.SilkS")
		)
		(fp_line
			(start -0.12065 -0.305054)
			(end -0.12065 -0.2794)
			(stroke
				(width 0.1)
				(type default)
			)
			(layer "F.Fab")
		)
		(fp_line
			(start -0.67945 -0.305054)
			(end -0.12065 -0.305054)
			(stroke
				(width 0.1)
				(type default)
			)
			(layer "F.Fab")
		)
		(fp_line
			(start 0.67945 -0.3048)
			(end 0.67945 0.3048)
			(stroke
				(width 0.1)
				(type default)
			)
			(layer "F.Fab")
		)
		(fp_line
			(start 0.12065 -0.3048)
			(end 0.67945 -0.3048)
			(stroke
				(width 0.1)
				(type default)
			)
			(layer "F.Fab")
		)
		(fp_line
			(start 0.12065 -0.2794)
			(end 0.12065 -0.3048)
			(stroke
				(width 0.1)
				(type default)
			)
			(layer "F.Fab")
		)
		(fp_line
			(start -0.12065 -0.2794)
			(end 0.12065 -0.2794)
			(stroke
				(width 0.1)
				(type default)
			)
			(layer "F.Fab")
		)
		(fp_line
			(start 0.120396 0.2794)
			(end -0.12065 0.2794)
			(stroke
				(width 0.1)
				(type default)
			)
			(layer "F.Fab")
		)
		(fp_line
			(start -0.12065 0.2794)
			(end -0.12065 0.3048)
			(stroke
				(width 0.1)
				(type default)
			)
			(layer "F.Fab")
		)
		(fp_line
			(start 0.67945 0.3048)
			(end 0.120396 0.3048)
			(stroke
				(width 0.1)
				(type default)
			)
			(layer "F.Fab")
		)
		(fp_line
			(start 0.120396 0.3048)
			(end 0.120396 0.2794)
			(stroke
				(width 0.1)
				(type default)
			)
			(layer "F.Fab")
		)
		(fp_line
			(start -0.12065 0.3048)
			(end -0.67945 0.3048)
			(stroke
				(width 0.1)
				(type default)
			)
			(layer "F.Fab")
		)
		(fp_line
			(start -0.67945 0.3048)
			(end -0.67945 -0.305054)
			(stroke
				(width 0.1)
				(type default)
			)
			(layer "F.Fab")
		)
		(pad "1" smd circle
			(at -0.40005 0 90)
			(size 0 0)
			(layers "F.Cu" "F.Mask" "F.Paste")
			(net "SW_P12V_AUX_PVDDCR_CPU0_P1_FLT")
		)
		(pad "2" smd circle
			(at 0.40005 0 90)
			(size 0 0)
			(layers "F.Cu" "F.Mask" "F.Paste")
			(net "GND")
		)
	)
	(footprint ""
		(layer "F.Cu")
		(at 366.06734 -384.32486 180)
		(property "Reference" "C899"
			(at 0 0 180)
			(layer "F.SilkS")
			(hide yes)
			(effects
				(font
					(size 1.27 1.27)
				)
			)
		)
		(property "Value" ""
			(at 0 0 180)
			(layer "F.Fab")
			(effects
				(font
					(size 1.27 1.27)
				)
			)
		)
		(duplicate_pad_numbers_are_jumpers no)
		(fp_line
			(start 0.299974 0.150114)
			(end -0.299974 0.150114)
			(stroke
				(width 0.1)
				(type default)
			)
			(layer "F.Fab")
		)
		(fp_line
			(start 0.299974 -0.150114)
			(end 0.299974 0.150114)
			(stroke
				(width 0.1)
				(type default)
			)
			(layer "F.Fab")
		)
		(fp_line
			(start -0.299974 0.150114)
			(end -0.299974 -0.150114)
			(stroke
				(width 0.1)
				(type default)
			)
			(layer "F.Fab")
		)
		(fp_line
			(start -0.299974 -0.150114)
			(end 0.299974 -0.150114)
			(stroke
				(width 0.1)
				(type default)
			)
			(layer "F.Fab")
		)
		(pad "1" smd rect
			(at -0.2667 0 180)
			(size 0.3048 0.381)
			(layers "F.Cu" "F.Mask" "F.Paste")
			(net "P5E_CPU0_P3_TX_C_DP<1>")
		)
		(pad "2" smd rect
			(at 0.2667 0 180)
			(size 0.3048 0.381)
			(layers "F.Cu" "F.Mask" "F.Paste")
			(net "P5E_CPU0_P3_TX_DP<1>")
		)
	)
	(footprint ""
		(layer "F.Cu")
		(at 330.731876 -70.098412 90)
		(property "Reference" "D77"
			(at -3.934714 -0.691642 90)
			(unlocked yes)
			(layer "F.SilkS")
			(effects
				(font
					(size 0.7874 0.5842)
					(thickness 0.1524)
				)
				(justify left)
			)
		)
		(property "Value" ""
			(at 0 0 90)
			(layer "F.Fab")
			(effects
				(font
					(size 1.27 1.27)
				)
			)
		)
		(duplicate_pad_numbers_are_jumpers no)
		(fp_line
			(start 1.16078 -0.4826)
			(end 1.16078 0.4826)
			(stroke
				(width 0.1524)
				(type default)
			)
			(layer "F.SilkS")
		)
		(fp_line
			(start 1.03378 -0.4826)
			(end 1.03378 0.4826)
			(stroke
				(width 0.1524)
				(type default)
			)
			(layer "F.SilkS")
		)
		(fp_line
			(start 0.90678 -0.4826)
			(end 0.90678 0.4826)
			(stroke
				(width 0.1524)
				(type default)
			)
			(layer "F.SilkS")
		)
		(fp_line
			(start -0.64008 -0.4826)
			(end 1.16078 -0.4826)
			(stroke
				(width 0.1524)
				(type default)
			)
			(layer "F.SilkS")
		)
		(fp_line
			(start -0.79248 -0.4826)
			(end 1.03378 -0.4826)
			(stroke
				(width 0.1524)
				(type default)
			)
			(layer "F.SilkS")
		)
		(fp_line
			(start -0.89408 -0.4826)
			(end 0.90678 -0.4826)
			(stroke
				(width 0.1524)
				(type default)
			)
			(layer "F.SilkS")
		)
		(fp_line
			(start 1.16078 0.4826)
			(end -0.64008 0.4826)
			(stroke
				(width 0.1524)
				(type default)
			)
			(layer "F.SilkS")
		)
		(fp_line
			(start 1.03378 0.4826)
			(end -0.79248 0.4826)
			(stroke
				(width 0.1524)
				(type default)
			)
			(layer "F.SilkS")
		)
		(fp_line
			(start 0.90678 0.4826)
			(end -0.90678 0.4826)
			(stroke
				(width 0.1524)
				(type default)
			)
			(layer "F.SilkS")
		)
		(fp_line
			(start -0.90678 0.4826)
			(end -0.90678 -0.4699)
			(stroke
				(width 0.1524)
				(type default)
			)
			(layer "F.SilkS")
		)
		(fp_line
			(start 0.499872 -0.249936)
			(end 0.499872 0.249936)
			(stroke
				(width 0.1)
				(type default)
			)
			(layer "F.Fab")
		)
		(fp_line
			(start -0.499872 -0.249936)
			(end 0.499872 -0.249936)
			(stroke
				(width 0.1)
				(type default)
			)
			(layer "F.Fab")
		)
		(fp_line
			(start 0.499872 0.249936)
			(end -0.499872 0.249936)
			(stroke
				(width 0.1)
				(type default)
			)
			(layer "F.Fab")
		)
		(fp_line
			(start -0.499872 0.249936)
			(end -0.499872 -0.249936)
			(stroke
				(width 0.1)
				(type default)
			)
			(layer "F.Fab")
		)
		(pad "A" smd rect
			(at -0.47498 0 90)
			(size 0.6096 0.7112)
			(layers "F.Cu" "F.Mask" "F.Paste")
			(net "LED_PWRGD_PVDDIO_P0_R")
		)
		(pad "C" smd rect
			(at 0.47498 0 90)
			(size 0.6096 0.7112)
			(layers "F.Cu" "F.Mask" "F.Paste")
			(net "LED_PWRGD_PVDDIO_P0_D")
		)
	)
)
